(kicad_pcb
	(version 20260206)
	(generator "pcbnew")
	(generator_version "10.0")
	(general
		(thickness 1.6)
		(legacy_teardrops no)
	)
	(paper "A4")
	(title_block
		(title "04192023_DAF0TMB3IC0_F0TG_MB_C_brd_V02_OCP.brd")
		(comment 1 "Grand Teton / footprints 2307-2313 of 8354")
	)
	(layers
		(0 "F.Cu" signal "TOP")
		(4 "In1.Cu" signal "GND")
		(6 "In2.Cu" signal "IN1")
		(8 "In3.Cu" signal "GND1")
		(10 "In4.Cu" signal "IN2")
		(12 "In5.Cu" signal "GND2")
		(14 "In6.Cu" signal "IN3")
		(16 "In7.Cu" signal "GND3")
		(18 "In8.Cu" signal "VCC")
		(20 "In9.Cu" signal "VCC1")
		(22 "In10.Cu" signal "GND4")
		(24 "In11.Cu" signal "IN4")
		(26 "In12.Cu" signal "GND5")
		(28 "In13.Cu" signal "IN5")
		(30 "In14.Cu" signal "GND6")
		(32 "In15.Cu" signal "IN6")
		(34 "In16.Cu" signal "GND7")
		(2 "B.Cu" signal "BOTTOM")
		(9 "F.Adhes" user "F.Adhesive")
		(11 "B.Adhes" user "B.Adhesive")
		(13 "F.Paste" user "Package Geometry/Pastemask Top")
		(15 "B.Paste" user "Package Geometry/Pastemask Bottom")
		(5 "F.SilkS" user "Ref Des/Silkscreen Top")
		(7 "B.SilkS" user "Ref Des/Silkscreen Bottom")
		(1 "F.Mask" user "Board Geometry/Soldermask Top")
		(3 "B.Mask" user "Board Geometry/Soldermask Bottom")
		(17 "Dwgs.User" user "User.Drawings")
		(19 "Cmts.User" user "User.Comments")
		(21 "Eco1.User" user "User.Eco1")
		(23 "Eco2.User" user "User.Eco2")
		(25 "Edge.Cuts" user "Board Geometry/Outline")
		(27 "Margin" user)
		(31 "F.CrtYd" user "Package Geometry/Place Bound Top")
		(29 "B.CrtYd" user "Package Geometry/Place Bound Bottom")
		(35 "F.Fab" user "Ref Des/Assembly Top")
		(33 "B.Fab" user "Ref Des/Assembly Bottom")
	)
	(footprint ""
		(layer "F.Cu")
		(at 154.690064 -69.665088 -90)
		(property "Reference" "J57"
			(at 2.393696 1.000252 0)
			(unlocked yes)
			(layer "F.SilkS")
			(effects
				(font
					(size 0.7874 0.5842)
					(thickness 0.1524)
				)
				(justify left)
			)
		)
		(property "Value" ""
			(at 0 0 270)
			(layer "F.Fab")
			(effects
				(font
					(size 1.27 1.27)
				)
			)
		)
		(duplicate_pad_numbers_are_jumpers no)
		(fp_line
			(start -1.234948 19.05)
			(end -1.234948 -1.27)
			(stroke
				(width 0.1524)
				(type default)
			)
			(layer "F.SilkS")
		)
		(fp_line
			(start 1.234948 19.05)
			(end -1.234948 19.05)
			(stroke
				(width 0.1524)
				(type default)
			)
			(layer "F.SilkS")
		)
		(fp_line
			(start -1.234948 -1.27)
			(end 1.234948 -1.27)
			(stroke
				(width 0.1524)
				(type default)
			)
			(layer "F.SilkS")
		)
		(fp_line
			(start 1.234948 -1.27)
			(end 1.234948 19.05)
			(stroke
				(width 0.1524)
				(type default)
			)
			(layer "F.SilkS")
		)
		(fp_poly
			(pts
				(xy -2.8194 0.635) (xy -2.8194 -0.5842) (xy -1.4986 0)
			)
			(stroke
				(width 0)
				(type default)
			)
			(fill yes)
			(layer "F.SilkS")
		)
		(fp_line
			(start -1.23698 19.05)
			(end -1.23698 -1.27)
			(stroke
				(width 0.1)
				(type default)
			)
			(layer "F.Fab")
		)
		(fp_line
			(start 1.23698 19.05)
			(end -1.23698 19.05)
			(stroke
				(width 0.1)
				(type default)
			)
			(layer "F.Fab")
		)
		(fp_line
			(start -1.23698 -1.27)
			(end 1.23698 -1.27)
			(stroke
				(width 0.1)
				(type default)
			)
			(layer "F.Fab")
		)
		(fp_line
			(start 1.23698 -1.27)
			(end 1.23698 19.05)
			(stroke
				(width 0.1)
				(type default)
			)
			(layer "F.Fab")
		)
		(fp_poly
			(pts
				(xy -1.4986 0) (xy -2.8194 -0.5842) (xy -2.8194 0.635)
			)
			(stroke
				(width 0)
				(type default)
			)
			(fill yes)
			(layer "F.Fab")
		)
		(fp_text user "8"
			(at -1.886966 18.1737 0)
			(unlocked yes)
			(layer "F.SilkS")
			(effects
				(font
					(size 0.7874 0.5842)
					(thickness 0.1524)
				)
				(justify left)
			)
		)
		(fp_text user "8"
			(at -0.085852 19.3421 180)
			(unlocked yes)
			(layer "B.SilkS")
			(effects
				(font
					(size 0.7874 0.5842)
					(thickness 0.1524)
				)
				(justify left mirror)
			)
		)
		(fp_text user "1"
			(at 0.015748 -0.9271 180)
			(unlocked yes)
			(layer "B.SilkS")
			(effects
				(font
					(size 0.7874 0.5842)
					(thickness 0.1524)
				)
				(justify left mirror)
			)
		)
		(fp_text user "8"
			(at -0.085852 19.3421 180)
			(unlocked yes)
			(layer "B.Fab")
			(effects
				(font
					(size 0.7874 0.5842)
					(thickness 0.1524)
				)
				(justify left mirror)
			)
		)
		(fp_text user "1"
			(at 0.015748 -0.9271 180)
			(unlocked yes)
			(layer "B.Fab")
			(effects
				(font
					(size 0.7874 0.5842)
					(thickness 0.1524)
				)
				(justify left mirror)
			)
		)
		(fp_text user "8"
			(at -1.965706 17.5895 180)
			(unlocked yes)
			(layer "F.Fab")
			(effects
				(font
					(size 0.7874 0.5842)
					(thickness 0.1524)
				)
				(justify left)
			)
		)
		(pad "1" thru_hole rect
			(at 0 0 180)
			(size 1.6764 1.6764)
			(drill 1.1684)
			(layers "*.Cu" "*.Mask")
			(remove_unused_layers no)
			(net "P3V3_AUX")
			(clearance 0)
			(padstack
				(mode front_inner_back)
				(layer "Inner"
					(shape circle)
					(size 1.6764 1.6764)
					(clearance 0)
				)
				(layer "B.Cu"
					(shape rect)
					(size 1.6764 1.6764)
					(clearance 0)
				)
			)
		)
		(pad "2" thru_hole circle
			(at 0 2.54 180)
			(size 1.6764 1.6764)
			(drill 1.1684)
			(layers "*.Cu" "*.Mask")
			(remove_unused_layers no)
			(net "JTAG_PLD_TDI")
			(clearance 0)
		)
		(pad "3" thru_hole circle
			(at 0 5.08 180)
			(size 1.6764 1.6764)
			(drill 1.1684)
			(layers "*.Cu" "*.Mask")
			(remove_unused_layers no)
			(net "JTAG_PLD_TDO")
			(clearance 0)
		)
		(pad "4" thru_hole circle
			(at 0 7.62 180)
			(size 1.6764 1.6764)
			(drill 1.1684)
			(layers "*.Cu" "*.Mask")
			(remove_unused_layers no)
			(net "Net_10747")
			(clearance 0)
		)
		(pad "5" thru_hole circle
			(at 0 10.16 180)
			(size 1.6764 1.6764)
			(drill 1.1684)
			(layers "*.Cu" "*.Mask")
			(remove_unused_layers no)
			(net "Net_10746")
			(clearance 0)
		)
		(pad "6" thru_hole circle
			(at 0 12.7 180)
			(size 1.6764 1.6764)
			(drill 1.1684)
			(layers "*.Cu" "*.Mask")
			(remove_unused_layers no)
			(net "JTAG_PLD_TMS")
			(clearance 0)
		)
		(pad "7" thru_hole circle
			(at 0 15.24 180)
			(size 1.6764 1.6764)
			(drill 1.1684)
			(layers "*.Cu" "*.Mask")
			(remove_unused_layers no)
			(net "GND")
			(clearance 0)
		)
		(pad "8" thru_hole circle
			(at 0 17.78 180)
			(size 1.6764 1.6764)
			(drill 1.1684)
			(layers "*.Cu" "*.Mask")
			(remove_unused_layers no)
			(net "JTAG_PLD_TCK")
			(clearance 0)
		)
	)
	(footprint ""
		(layer "F.Cu")
		(at 16.364458 -418.690298 90)
		(property "Reference" "R6179"
			(at 0 0 90)
			(layer "F.SilkS")
			(hide yes)
			(effects
				(font
					(size 1.27 1.27)
				)
			)
		)
		(property "Value" ""
			(at 0 0 90)
			(layer "F.Fab")
			(effects
				(font
					(size 1.27 1.27)
				)
			)
		)
		(duplicate_pad_numbers_are_jumpers no)
		(fp_line
			(start 0.7874 -0.4064)
			(end 0.7874 0.4064)
			(stroke
				(width 0.1524)
				(type default)
			)
			(layer "F.SilkS")
		)
		(fp_line
			(start -0.7874 -0.4064)
			(end 0.7874 -0.4064)
			(stroke
				(width 0.1524)
				(type default)
			)
			(layer "F.SilkS")
		)
		(fp_line
			(start 0.7874 0.4064)
			(end -0.7874 0.4064)
			(stroke
				(width 0.1524)
				(type default)
			)
			(layer "F.SilkS")
		)
		(fp_line
			(start -0.7874 0.4064)
			(end -0.7874 -0.4064)
			(stroke
				(width 0.1524)
				(type default)
			)
			(layer "F.SilkS")
		)
		(fp_line
			(start -0.12065 -0.305054)
			(end -0.12065 -0.2794)
			(stroke
				(width 0.1)
				(type default)
			)
			(layer "F.Fab")
		)
		(fp_line
			(start -0.67945 -0.305054)
			(end -0.12065 -0.305054)
			(stroke
				(width 0.1)
				(type default)
			)
			(layer "F.Fab")
		)
		(fp_line
			(start 0.67945 -0.3048)
			(end 0.67945 0.3048)
			(stroke
				(width 0.1)
				(type default)
			)
			(layer "F.Fab")
		)
		(fp_line
			(start 0.12065 -0.3048)
			(end 0.67945 -0.3048)
			(stroke
				(width 0.1)
				(type default)
			)
			(layer "F.Fab")
		)
		(fp_line
			(start 0.12065 -0.2794)
			(end 0.12065 -0.3048)
			(stroke
				(width 0.1)
				(type default)
			)
			(layer "F.Fab")
		)
		(fp_line
			(start -0.12065 -0.2794)
			(end 0.12065 -0.2794)
			(stroke
				(width 0.1)
				(type default)
			)
			(layer "F.Fab")
		)
		(fp_line
			(start 0.120396 0.2794)
			(end -0.12065 0.2794)
			(stroke
				(width 0.1)
				(type default)
			)
			(layer "F.Fab")
		)
		(fp_line
			(start -0.12065 0.2794)
			(end -0.12065 0.3048)
			(stroke
				(width 0.1)
				(type default)
			)
			(layer "F.Fab")
		)
		(fp_line
			(start 0.67945 0.3048)
			(end 0.120396 0.3048)
			(stroke
				(width 0.1)
				(type default)
			)
			(layer "F.Fab")
		)
		(fp_line
			(start 0.120396 0.3048)
			(end 0.120396 0.2794)
			(stroke
				(width 0.1)
				(type default)
			)
			(layer "F.Fab")
		)
		(fp_line
			(start -0.12065 0.3048)
			(end -0.67945 0.3048)
			(stroke
				(width 0.1)
				(type default)
			)
			(layer "F.Fab")
		)
		(fp_line
			(start -0.67945 0.3048)
			(end -0.67945 -0.305054)
			(stroke
				(width 0.1)
				(type default)
			)
			(layer "F.Fab")
		)
		(pad "1" smd circle
			(at -0.40005 0 90)
			(size 0 0)
			(layers "F.Cu" "F.Mask" "F.Paste")
			(net "P3V3_AUX")
		)
		(pad "2" smd circle
			(at 0.40005 0 90)
			(size 0 0)
			(layers "F.Cu" "F.Mask" "F.Paste")
			(net "FM_P2E_BUF2_VOD_SEL")
		)
	)
	(footprint ""
		(layer "F.Cu")
		(at 359.416096 -256.012188 90)
		(property "Reference" "C3929"
			(at 0 0 90)
			(layer "F.SilkS")
			(hide yes)
			(effects
				(font
					(size 1.27 1.27)
				)
			)
		)
		(property "Value" ""
			(at 0 0 90)
			(layer "F.Fab")
			(effects
				(font
					(size 1.27 1.27)
				)
			)
		)
		(duplicate_pad_numbers_are_jumpers no)
		(fp_line
			(start 0.7874 -0.4064)
			(end 0.7874 0.4064)
			(stroke
				(width 0.1524)
				(type default)
			)
			(layer "F.SilkS")
		)
		(fp_line
			(start -0.7874 -0.4064)
			(end 0.7874 -0.4064)
			(stroke
				(width 0.1524)
				(type default)
			)
			(layer "F.SilkS")
		)
		(fp_line
			(start 0.7874 0.4064)
			(end -0.7874 0.4064)
			(stroke
				(width 0.1524)
				(type default)
			)
			(layer "F.SilkS")
		)
		(fp_line
			(start -0.7874 0.4064)
			(end -0.7874 -0.4064)
			(stroke
				(width 0.1524)
				(type default)
			)
			(layer "F.SilkS")
		)
		(fp_line
			(start -0.12065 -0.305054)
			(end -0.12065 -0.2794)
			(stroke
				(width 0.1)
				(type default)
			)
			(layer "F.Fab")
		)
		(fp_line
			(start -0.67945 -0.305054)
			(end -0.12065 -0.305054)
			(stroke
				(width 0.1)
				(type default)
			)
			(layer "F.Fab")
		)
		(fp_line
			(start 0.67945 -0.3048)
			(end 0.67945 0.3048)
			(stroke
				(width 0.1)
				(type default)
			)
			(layer "F.Fab")
		)
		(fp_line
			(start 0.12065 -0.3048)
			(end 0.67945 -0.3048)
			(stroke
				(width 0.1)
				(type default)
			)
			(layer "F.Fab")
		)
		(fp_line
			(start 0.12065 -0.2794)
			(end 0.12065 -0.3048)
			(stroke
				(width 0.1)
				(type default)
			)
			(layer "F.Fab")
		)
		(fp_line
			(start -0.12065 -0.2794)
			(end 0.12065 -0.2794)
			(stroke
				(width 0.1)
				(type default)
			)
			(layer "F.Fab")
		)
		(fp_line
			(start 0.120396 0.2794)
			(end -0.12065 0.2794)
			(stroke
				(width 0.1)
				(type default)
			)
			(layer "F.Fab")
		)
		(fp_line
			(start -0.12065 0.2794)
			(end -0.12065 0.3048)
			(stroke
				(width 0.1)
				(type default)
			)
			(layer "F.Fab")
		)
		(fp_line
			(start 0.67945 0.3048)
			(end 0.120396 0.3048)
			(stroke
				(width 0.1)
				(type default)
			)
			(layer "F.Fab")
		)
		(fp_line
			(start 0.120396 0.3048)
			(end 0.120396 0.2794)
			(stroke
				(width 0.1)
				(type default)
			)
			(layer "F.Fab")
		)
		(fp_line
			(start -0.12065 0.3048)
			(end -0.67945 0.3048)
			(stroke
				(width 0.1)
				(type default)
			)
			(layer "F.Fab")
		)
		(fp_line
			(start -0.67945 0.3048)
			(end -0.67945 -0.305054)
			(stroke
				(width 0.1)
				(type default)
			)
			(layer "F.Fab")
		)
		(pad "1" smd circle
			(at -0.40005 0 90)
			(size 0 0)
			(layers "F.Cu" "F.Mask" "F.Paste")
			(net "PVDDCR_SOC_P0")
		)
		(pad "2" smd circle
			(at 0.40005 0 90)
			(size 0 0)
			(layers "F.Cu" "F.Mask" "F.Paste")
			(net "GND")
		)
	)
	(footprint ""
		(layer "F.Cu")
		(at 75.517502 -373.03583 -90)
		(property "Reference" "C737"
			(at 0 0 270)
			(layer "F.SilkS")
			(hide yes)
			(effects
				(font
					(size 1.27 1.27)
				)
			)
		)
		(property "Value" ""
			(at 0 0 270)
			(layer "F.Fab")
			(effects
				(font
					(size 1.27 1.27)
				)
			)
		)
		(duplicate_pad_numbers_are_jumpers no)
		(fp_line
			(start -0.299974 0.150114)
			(end -0.299974 -0.150114)
			(stroke
				(width 0.1)
				(type default)
			)
			(layer "F.Fab")
		)
		(fp_line
			(start 0.299974 0.150114)
			(end -0.299974 0.150114)
			(stroke
				(width 0.1)
				(type default)
			)
			(layer "F.Fab")
		)
		(fp_line
			(start -0.299974 -0.150114)
			(end 0.299974 -0.150114)
			(stroke
				(width 0.1)
				(type default)
			)
			(layer "F.Fab")
		)
		(fp_line
			(start 0.299974 -0.150114)
			(end 0.299974 0.150114)
			(stroke
				(width 0.1)
				(type default)
			)
			(layer "F.Fab")
		)
		(pad "1" smd rect
			(at -0.2667 0 270)
			(size 0.3048 0.381)
			(layers "F.Cu" "F.Mask" "F.Paste")
			(net "P5E_CPU1_P1_TX_C_DP<2>")
		)
		(pad "2" smd rect
			(at 0.2667 0 270)
			(size 0.3048 0.381)
			(layers "F.Cu" "F.Mask" "F.Paste")
			(net "P5E_CPU1_P1_TX_DP<2>")
		)
	)
	(footprint ""
		(layer "F.Cu")
		(at 61.81471 -337.403948)
		(property "Reference" "PL43"
			(at -3.115056 -15.633446 0)
			(unlocked yes)
			(layer "F.SilkS")
			(effects
				(font
					(size 0.7874 0.5842)
					(thickness 0.1524)
				)
				(justify left)
			)
		)
		(property "Value" ""
			(at 0 0 0)
			(layer "F.Fab")
			(effects
				(font
					(size 1.27 1.27)
				)
			)
		)
		(duplicate_pad_numbers_are_jumpers no)
		(fp_line
			(start -3.750056 -5.500116)
			(end -2.393442 -5.500116)
			(stroke
				(width 0.1524)
				(type default)
			)
			(layer "F.SilkS")
		)
		(fp_line
			(start -3.750056 5.500116)
			(end -3.750056 -5.500116)
			(stroke
				(width 0.1524)
				(type default)
			)
			(layer "F.SilkS")
		)
		(fp_line
			(start -2.393442 5.500116)
			(end -3.750056 5.500116)
			(stroke
				(width 0.1524)
				(type default)
			)
			(layer "F.SilkS")
		)
		(fp_line
			(start 2.393442 5.500116)
			(end 3.750056 5.500116)
			(stroke
				(width 0.1524)
				(type default)
			)
			(layer "F.SilkS")
		)
		(fp_line
			(start 3.750056 -5.500116)
			(end 2.393442 -5.500116)
			(stroke
				(width 0.1524)
				(type default)
			)
			(layer "F.SilkS")
		)
		(fp_line
			(start 3.750056 5.500116)
			(end 3.750056 -5.500116)
			(stroke
				(width 0.1524)
				(type default)
			)
			(layer "F.SilkS")
		)
		(fp_poly
			(pts
				(xy -3.9116 -4.249928) (xy -4.3434 -4.034028) (xy -4.3434 -4.465828)
			)
			(stroke
				(width 0)
				(type default)
			)
			(fill yes)
			(layer "F.SilkS")
		)
		(fp_line
			(start -3.750056 -5.500116)
			(end -3.750056 5.500116)
			(stroke
				(width 0.1)
				(type default)
			)
			(layer "F.Fab")
		)
		(fp_line
			(start -3.750056 5.500116)
			(end 3.750056 5.500116)
			(stroke
				(width 0.1)
				(type default)
			)
			(layer "F.Fab")
		)
		(fp_line
			(start 3.750056 -5.500116)
			(end -3.750056 -5.500116)
			(stroke
				(width 0.1)
				(type default)
			)
			(layer "F.Fab")
		)
		(fp_line
			(start 3.750056 5.500116)
			(end 3.750056 -5.500116)
			(stroke
				(width 0.1)
				(type default)
			)
			(layer "F.Fab")
		)
		(fp_poly
			(pts
				(xy -4.9276 -4.757928) (xy -4.9276 -3.741928) (xy -3.9116 -4.249928)
			)
			(stroke
				(width 0)
				(type default)
			)
			(fill yes)
			(layer "F.Fab")
		)
		(pad "1" smd rect
			(at 0 -4.249928 270)
			(size 2.413 4.5212)
			(layers "F.Cu" "F.Mask" "F.Paste")
			(net "SW_PVDDCR_CPU1_P1_SW4")
		)
		(pad "2" smd rect
			(at 0 -1.175004 270)
			(size 1.3716 4.5212)
			(layers "F.Cu" "F.Mask" "F.Paste")
			(net "IND_CPU1_P1_CPL3")
		)
		(pad "3" smd rect
			(at 0 1.175004 270)
			(size 1.3716 4.5212)
			(layers "F.Cu" "F.Mask" "F.Paste")
			(net "GND")
		)
		(pad "4" smd rect
			(at 0 4.249928 270)
			(size 2.413 4.5212)
			(layers "F.Cu" "F.Mask" "F.Paste")
			(net "PVDDCR_CPU1_P1")
		)
	)
	(footprint ""
		(layer "F.Cu")
		(at 204.7621 -408.084782)
		(property "Reference" "PR3917"
			(at 0 0 0)
			(layer "F.SilkS")
			(hide yes)
			(effects
				(font
					(size 1.27 1.27)
				)
			)
		)
		(property "Value" ""
			(at 0 0 0)
			(layer "F.Fab")
			(effects
				(font
					(size 1.27 1.27)
				)
			)
		)
		(duplicate_pad_numbers_are_jumpers no)
		(fp_line
			(start -0.7874 -0.4064)
			(end 0.7874 -0.4064)
			(stroke
				(width 0.1524)
				(type default)
			)
			(layer "F.SilkS")
		)
		(fp_line
			(start -0.7874 0.4064)
			(end -0.7874 -0.4064)
			(stroke
				(width 0.1524)
				(type default)
			)
			(layer "F.SilkS")
		)
		(fp_line
			(start 0.7874 -0.4064)
			(end 0.7874 0.4064)
			(stroke
				(width 0.1524)
				(type default)
			)
			(layer "F.SilkS")
		)
		(fp_line
			(start 0.7874 0.4064)
			(end -0.7874 0.4064)
			(stroke
				(width 0.1524)
				(type default)
			)
			(layer "F.SilkS")
		)
		(fp_line
			(start -0.67945 -0.305054)
			(end -0.12065 -0.305054)
			(stroke
				(width 0.1)
				(type default)
			)
			(layer "F.Fab")
		)
		(fp_line
			(start -0.67945 0.3048)
			(end -0.67945 -0.305054)
			(stroke
				(width 0.1)
				(type default)
			)
			(layer "F.Fab")
		)
		(fp_line
			(start -0.12065 -0.305054)
			(end -0.12065 -0.2794)
			(stroke
				(width 0.1)
				(type default)
			)
			(layer "F.Fab")
		)
		(fp_line
			(start -0.12065 -0.2794)
			(end 0.12065 -0.2794)
			(stroke
				(width 0.1)
				(type default)
			)
			(layer "F.Fab")
		)
		(fp_line
			(start -0.12065 0.2794)
			(end -0.12065 0.3048)
			(stroke
				(width 0.1)
				(type default)
			)
			(layer "F.Fab")
		)
		(fp_line
			(start -0.12065 0.3048)
			(end -0.67945 0.3048)
			(stroke
				(width 0.1)
				(type default)
			)
			(layer "F.Fab")
		)
		(fp_line
			(start 0.120396 0.2794)
			(end -0.12065 0.2794)
			(stroke
				(width 0.1)
				(type default)
			)
			(layer "F.Fab")
		)
		(fp_line
			(start 0.120396 0.3048)
			(end 0.120396 0.2794)
			(stroke
				(width 0.1)
				(type default)
			)
			(layer "F.Fab")
		)
		(fp_line
			(start 0.12065 -0.3048)
			(end 0.67945 -0.3048)
			(stroke
				(width 0.1)
				(type default)
			)
			(layer "F.Fab")
		)
		(fp_line
			(start 0.12065 -0.2794)
			(end 0.12065 -0.3048)
			(stroke
				(width 0.1)
				(type default)
			)
			(layer "F.Fab")
		)
		(fp_line
			(start 0.67945 -0.3048)
			(end 0.67945 0.3048)
			(stroke
				(width 0.1)
				(type default)
			)
			(layer "F.Fab")
		)
		(fp_line
			(start 0.67945 0.3048)
			(end 0.120396 0.3048)
			(stroke
				(width 0.1)
				(type default)
			)
			(layer "F.Fab")
		)
		(pad "1" smd circle
			(at -0.40005 0)
			(size 0 0)
			(layers "F.Cu" "F.Mask" "F.Paste")
			(net "HSC_SCREF")
		)
		(pad "2" smd circle
			(at 0.40005 0)
			(size 0 0)
			(layers "F.Cu" "F.Mask" "F.Paste")
			(net "HSC_SCREF_2")
		)
	)
	(footprint ""
		(layer "F.Cu")
		(at 104.1908 -392.2268)
		(property "Reference" "R1372"
			(at 0 0 0)
			(layer "F.SilkS")
			(hide yes)
			(effects
				(font
					(size 1.27 1.27)
				)
			)
		)
		(property "Value" ""
			(at 0 0 0)
			(layer "F.Fab")
			(effects
				(font
					(size 1.27 1.27)
				)
			)
		)
		(duplicate_pad_numbers_are_jumpers no)
		(fp_line
			(start -0.32512 -0.175006)
			(end 0.32512 -0.175006)
			(stroke
				(width 0.1)
				(type default)
			)
			(layer "F.Fab")
		)
		(fp_line
			(start -0.32512 0.175006)
			(end -0.32512 -0.175006)
			(stroke
				(width 0.1)
				(type default)
			)
			(layer "F.Fab")
		)
		(fp_line
			(start 0.32512 -0.175006)
			(end 0.32512 0.175006)
			(stroke
				(width 0.1)
				(type default)
			)
			(layer "F.Fab")
		)
		(fp_line
			(start 0.32512 0.175006)
			(end -0.32512 0.175006)
			(stroke
				(width 0.1)
				(type default)
			)
			(layer "F.Fab")
		)
		(pad "1" smd rect
			(at -0.2667 0)
			(size 0.3048 0.381)
			(layers "F.Cu" "F.Mask" "F.Paste")
			(net "JTAG_TRST_RT_CPU1_P1_N")
		)
		(pad "2" smd rect
			(at 0.2667 0 180)
			(size 0.3048 0.381)
			(layers "F.Cu" "F.Mask" "F.Paste")
			(net "GND")
		)
	)
)
